# T6G (Grand Teton) — schematic netlist excerpt (pin names and nets, part order shuffled) for the footprints in the layout excerpt that follows; sources: Cadence DE-HDL packaged netlist, KiCad conversion of 04192023_DAF0TMB3IC0_F0TG_MB_C_brd_V02_OCP.brd

PC251  Q_CAP  10UF 6.3V 20% X6S  pkg C0402  page 210 : A = PVDDCR_CPU0_P1_VCCS ; B = GND
C2538  Q_CAP  22UF 4V 20% X6S  pkg C0402  page 70 : A = PVDDCR_SOC_P0 ; B = GND

(kicad_pcb
	(version 20260206)
	(generator "pcbnew")
	(generator_version "10.0")
	(general
		(thickness 1.6)
		(legacy_teardrops no)
	)
	(paper "A4")
	(title_block
		(title "04192023_DAF0TMB3IC0_F0TG_MB_C_brd_V02_OCP.brd")
		(comment 1 "Grand Teton / footprints 6165-6166 of 8354")
	)
	(layers
		(0 "F.Cu" signal "TOP")
		(4 "In1.Cu" signal "GND")
		(6 "In2.Cu" signal "IN1")
		(8 "In3.Cu" signal "GND1")
		(10 "In4.Cu" signal "IN2")
		(12 "In5.Cu" signal "GND2")
		(14 "In6.Cu" signal "IN3")
		(16 "In7.Cu" signal "GND3")
		(18 "In8.Cu" signal "VCC")
		(20 "In9.Cu" signal "VCC1")
		(22 "In10.Cu" signal "GND4")
		(24 "In11.Cu" signal "IN4")
		(26 "In12.Cu" signal "GND5")
		(28 "In13.Cu" signal "IN5")
		(30 "In14.Cu" signal "GND6")
		(32 "In15.Cu" signal "IN6")
		(34 "In16.Cu" signal "GND7")
		(2 "B.Cu" signal "BOTTOM")
		(9 "F.Adhes" user "F.Adhesive")
		(11 "B.Adhes" user "B.Adhesive")
		(13 "F.Paste" user "Package Geometry/Pastemask Top")
		(15 "B.Paste" user "Package Geometry/Pastemask Bottom")
		(5 "F.SilkS" user "Ref Des/Silkscreen Top")
		(7 "B.SilkS" user "Ref Des/Silkscreen Bottom")
		(1 "F.Mask" user "Board Geometry/Soldermask Top")
		(3 "B.Mask" user "Board Geometry/Soldermask Bottom")
		(17 "Dwgs.User" user "User.Drawings")
		(19 "Cmts.User" user "User.Comments")
		(21 "Eco1.User" user "User.Eco1")
		(23 "Eco2.User" user "User.Eco2")
		(25 "Edge.Cuts" user "Board Geometry/Outline")
		(27 "Margin" user)
		(31 "F.CrtYd" user "Package Geometry/Place Bound Top")
		(29 "B.CrtYd" user "Package Geometry/Place Bound Bottom")
		(35 "F.Fab" user "Ref Des/Assembly Top")
		(33 "B.Fab" user "Ref Des/Assembly Bottom")
	)
	(footprint ""
		(layer "B.Cu")
		(at 99.480878 -139.93241 90)
		(property "Reference" "PC251"
			(at 0 0 90)
			(layer "B.SilkS")
			(hide yes)
			(effects
				(font
					(size 1.27 1.27)
				)
				(justify mirror)
			)
		)
		(property "Value" ""
			(at 0 0 90)
			(layer "B.Fab")
			(effects
				(font
					(size 1.27 1.27)
				)
				(justify mirror)
			)
		)
		(duplicate_pad_numbers_are_jumpers no)
		(fp_line
			(start 0.7874 -0.4064)
			(end -0.7874 -0.4064)
			(stroke
				(width 0.1524)
				(type default)
			)
			(layer "B.SilkS")
		)
		(fp_line
			(start -0.7874 -0.4064)
			(end -0.7874 0.4064)
			(stroke
				(width 0.1524)
				(type default)
			)
			(layer "B.SilkS")
		)
		(fp_line
			(start 0.7874 0.4064)
			(end 0.7874 -0.4064)
			(stroke
				(width 0.1524)
				(type default)
			)
			(layer "B.SilkS")
		)
		(fp_line
			(start -0.7874 0.4064)
			(end 0.7874 0.4064)
			(stroke
				(width 0.1524)
				(type default)
			)
			(layer "B.SilkS")
		)
		(fp_line
			(start 0.67945 -0.305054)
			(end 0.12065 -0.305054)
			(stroke
				(width 0.1)
				(type default)
			)
			(layer "B.Fab")
		)
		(fp_line
			(start 0.12065 -0.305054)
			(end 0.12065 -0.2794)
			(stroke
				(width 0.1)
				(type default)
			)
			(layer "B.Fab")
		)
		(fp_line
			(start -0.12065 -0.3048)
			(end -0.67945 -0.3048)
			(stroke
				(width 0.1)
				(type default)
			)
			(layer "B.Fab")
		)
		(fp_line
			(start -0.67945 -0.3048)
			(end -0.67945 0.3048)
			(stroke
				(width 0.1)
				(type default)
			)
			(layer "B.Fab")
		)
		(fp_line
			(start 0.12065 -0.2794)
			(end -0.12065 -0.2794)
			(stroke
				(width 0.1)
				(type default)
			)
			(layer "B.Fab")
		)
		(fp_line
			(start -0.12065 -0.2794)
			(end -0.12065 -0.3048)
			(stroke
				(width 0.1)
				(type default)
			)
			(layer "B.Fab")
		)
		(fp_line
			(start 0.12065 0.2794)
			(end 0.12065 0.3048)
			(stroke
				(width 0.1)
				(type default)
			)
			(layer "B.Fab")
		)
		(fp_line
			(start -0.120396 0.2794)
			(end 0.12065 0.2794)
			(stroke
				(width 0.1)
				(type default)
			)
			(layer "B.Fab")
		)
		(fp_line
			(start 0.67945 0.3048)
			(end 0.67945 -0.305054)
			(stroke
				(width 0.1)
				(type default)
			)
			(layer "B.Fab")
		)
		(fp_line
			(start 0.12065 0.3048)
			(end 0.67945 0.3048)
			(stroke
				(width 0.1)
				(type default)
			)
			(layer "B.Fab")
		)
		(fp_line
			(start -0.120396 0.3048)
			(end -0.120396 0.2794)
			(stroke
				(width 0.1)
				(type default)
			)
			(layer "B.Fab")
		)
		(fp_line
			(start -0.67945 0.3048)
			(end -0.120396 0.3048)
			(stroke
				(width 0.1)
				(type default)
			)
			(layer "B.Fab")
		)
		(pad "1" smd circle
			(at 0.40005 0 270)
			(size 0 0)
			(layers "B.Cu" "B.Mask" "B.Paste")
			(net "PVDDCR_CPU0_P1_VCCS")
		)
		(pad "2" smd circle
			(at -0.40005 0 270)
			(size 0 0)
			(layers "B.Cu" "B.Mask" "B.Paste")
			(net "GND")
		)
	)
	(footprint ""
		(layer "B.Cu")
		(at 372.313454 -262.824976)
		(property "Reference" "C2538"
			(at 0 0 0)
			(layer "B.SilkS")
			(hide yes)
			(effects
				(font
					(size 1.27 1.27)
				)
				(justify mirror)
			)
		)
		(property "Value" ""
			(at 0 0 0)
			(layer "B.Fab")
			(effects
				(font
					(size 1.27 1.27)
				)
				(justify mirror)
			)
		)
		(duplicate_pad_numbers_are_jumpers no)
		(fp_line
			(start -0.7874 -0.4064)
			(end -0.7874 0.4064)
			(stroke
				(width 0.1524)
				(type default)
			)
			(layer "B.SilkS")
		)
		(fp_line
			(start -0.7874 0.4064)
			(end 0.7874 0.4064)
			(stroke
				(width 0.1524)
				(type default)
			)
			(layer "B.SilkS")
		)
		(fp_line
			(start 0.7874 -0.4064)
			(end -0.7874 -0.4064)
			(stroke
				(width 0.1524)
				(type default)
			)
			(layer "B.SilkS")
		)
		(fp_line
			(start 0.7874 0.4064)
			(end 0.7874 -0.4064)
			(stroke
				(width 0.1524)
				(type default)
			)
			(layer "B.SilkS")
		)
		(fp_line
			(start -0.67945 -0.3048)
			(end -0.67945 0.3048)
			(stroke
				(width 0.1)
				(type default)
			)
			(layer "B.Fab")
		)
		(fp_line
			(start -0.67945 0.3048)
			(end -0.120396 0.3048)
			(stroke
				(width 0.1)
				(type default)
			)
			(layer "B.Fab")
		)
		(fp_line
			(start -0.12065 -0.3048)
			(end -0.67945 -0.3048)
			(stroke
				(width 0.1)
				(type default)
			)
			(layer "B.Fab")
		)
		(fp_line
			(start -0.12065 -0.2794)
			(end -0.12065 -0.3048)
			(stroke
				(width 0.1)
				(type default)
			)
			(layer "B.Fab")
		)
		(fp_line
			(start -0.120396 0.2794)
			(end 0.12065 0.2794)
			(stroke
				(width 0.1)
				(type default)
			)
			(layer "B.Fab")
		)
		(fp_line
			(start -0.120396 0.3048)
			(end -0.120396 0.2794)
			(stroke
				(width 0.1)
				(type default)
			)
			(layer "B.Fab")
		)
		(fp_line
			(start 0.12065 -0.305054)
			(end 0.12065 -0.2794)
			(stroke
				(width 0.1)
				(type default)
			)
			(layer "B.Fab")
		)
		(fp_line
			(start 0.12065 -0.2794)
			(end -0.12065 -0.2794)
			(stroke
				(width 0.1)
				(type default)
			)
			(layer "B.Fab")
		)
		(fp_line
			(start 0.12065 0.2794)
			(end 0.12065 0.3048)
			(stroke
				(width 0.1)
				(type default)
			)
			(layer "B.Fab")
		)
		(fp_line
			(start 0.12065 0.3048)
			(end 0.67945 0.3048)
			(stroke
				(width 0.1)
				(type default)
			)
			(layer "B.Fab")
		)
		(fp_line
			(start 0.67945 -0.305054)
			(end 0.12065 -0.305054)
			(stroke
				(width 0.1)
				(type default)
			)
			(layer "B.Fab")
		)
		(fp_line
			(start 0.67945 0.3048)
			(end 0.67945 -0.305054)
			(stroke
				(width 0.1)
				(type default)
			)
			(layer "B.Fab")
		)
		(pad "1" smd circle
			(at 0.40005 0 180)
			(size 0 0)
			(layers "B.Cu" "B.Mask" "B.Paste")
			(net "PVDDCR_SOC_P0")
		)
		(pad "2" smd circle
			(at -0.40005 0 180)
			(size 0 0)
			(layers "B.Cu" "B.Mask" "B.Paste")
			(net "GND")
		)
	)
)
